# T6G (Grand Teton) — schematic netlist excerpt (pin names and nets, part order shuffled) for the footprints in the layout excerpt that follows; sources: Cadence DE-HDL packaged netlist, KiCad conversion of 04192023_DAF0TMB3IC0_F0TG_MB_C_brd_V02_OCP.brd

R353  Q_RES  0 5% CHIP  pkg 0402LF  page 267 : A = P12V_HSC_T_CRIT_N ; B = P12V_HSC_T_CRIT_R_N
L29  Q_INDUCTOR  BLM15PD121SN1D/1300MA IND  pkg SMLF  page 301 : \1\ = P1V8_CPU0_RT_1D ; \2\ = P1V8_CPU0_RT2_1A_1D

(kicad_pcb
	(version 20260206)
	(generator "pcbnew")
	(generator_version "10.0")
	(general
		(thickness 1.6)
		(legacy_teardrops no)
	)
	(paper "A4")
	(title_block
		(title "04192023_DAF0TMB3IC0_F0TG_MB_C_brd_V02_OCP.brd")
		(comment 1 "Grand Teton / footprints 950-951 of 8354")
	)
	(layers
		(0 "F.Cu" signal "TOP")
		(4 "In1.Cu" signal "GND")
		(6 "In2.Cu" signal "IN1")
		(8 "In3.Cu" signal "GND1")
		(10 "In4.Cu" signal "IN2")
		(12 "In5.Cu" signal "GND2")
		(14 "In6.Cu" signal "IN3")
		(16 "In7.Cu" signal "GND3")
		(18 "In8.Cu" signal "VCC")
		(20 "In9.Cu" signal "VCC1")
		(22 "In10.Cu" signal "GND4")
		(24 "In11.Cu" signal "IN4")
		(26 "In12.Cu" signal "GND5")
		(28 "In13.Cu" signal "IN5")
		(30 "In14.Cu" signal "GND6")
		(32 "In15.Cu" signal "IN6")
		(34 "In16.Cu" signal "GND7")
		(2 "B.Cu" signal "BOTTOM")
		(9 "F.Adhes" user "F.Adhesive")
		(11 "B.Adhes" user "B.Adhesive")
		(13 "F.Paste" user "Package Geometry/Pastemask Top")
		(15 "B.Paste" user "Package Geometry/Pastemask Bottom")
		(5 "F.SilkS" user "Ref Des/Silkscreen Top")
		(7 "B.SilkS" user "Ref Des/Silkscreen Bottom")
		(1 "F.Mask" user "Board Geometry/Soldermask Top")
		(3 "B.Mask" user "Board Geometry/Soldermask Bottom")
		(17 "Dwgs.User" user "User.Drawings")
		(19 "Cmts.User" user "User.Comments")
		(21 "Eco1.User" user "User.Eco1")
		(23 "Eco2.User" user "User.Eco2")
		(25 "Edge.Cuts" user "Board Geometry/Outline")
		(27 "Margin" user)
		(31 "F.CrtYd" user "Package Geometry/Place Bound Top")
		(29 "B.CrtYd" user "Package Geometry/Place Bound Bottom")
		(35 "F.Fab" user "Ref Des/Assembly Top")
		(33 "B.Fab" user "Ref Des/Assembly Bottom")
	)
	(footprint ""
		(layer "F.Cu")
		(at 283.21127 -401.586954 90)
		(property "Reference" "R353"
			(at 0 0 90)
			(layer "F.SilkS")
			(hide yes)
			(effects
				(font
					(size 1.27 1.27)
				)
			)
		)
		(property "Value" ""
			(at 0 0 90)
			(layer "F.Fab")
			(effects
				(font
					(size 1.27 1.27)
				)
			)
		)
		(duplicate_pad_numbers_are_jumpers no)
		(fp_line
			(start 0.7874 -0.4064)
			(end 0.7874 0.4064)
			(stroke
				(width 0.1524)
				(type default)
			)
			(layer "F.SilkS")
		)
		(fp_line
			(start -0.7874 -0.4064)
			(end 0.7874 -0.4064)
			(stroke
				(width 0.1524)
				(type default)
			)
			(layer "F.SilkS")
		)
		(fp_line
			(start 0.7874 0.4064)
			(end -0.7874 0.4064)
			(stroke
				(width 0.1524)
				(type default)
			)
			(layer "F.SilkS")
		)
		(fp_line
			(start -0.7874 0.4064)
			(end -0.7874 -0.4064)
			(stroke
				(width 0.1524)
				(type default)
			)
			(layer "F.SilkS")
		)
		(fp_line
			(start -0.12065 -0.305054)
			(end -0.12065 -0.2794)
			(stroke
				(width 0.1)
				(type default)
			)
			(layer "F.Fab")
		)
		(fp_line
			(start -0.67945 -0.305054)
			(end -0.12065 -0.305054)
			(stroke
				(width 0.1)
				(type default)
			)
			(layer "F.Fab")
		)
		(fp_line
			(start 0.67945 -0.3048)
			(end 0.67945 0.3048)
			(stroke
				(width 0.1)
				(type default)
			)
			(layer "F.Fab")
		)
		(fp_line
			(start 0.12065 -0.3048)
			(end 0.67945 -0.3048)
			(stroke
				(width 0.1)
				(type default)
			)
			(layer "F.Fab")
		)
		(fp_line
			(start 0.12065 -0.2794)
			(end 0.12065 -0.3048)
			(stroke
				(width 0.1)
				(type default)
			)
			(layer "F.Fab")
		)
		(fp_line
			(start -0.12065 -0.2794)
			(end 0.12065 -0.2794)
			(stroke
				(width 0.1)
				(type default)
			)
			(layer "F.Fab")
		)
		(fp_line
			(start 0.120396 0.2794)
			(end -0.12065 0.2794)
			(stroke
				(width 0.1)
				(type default)
			)
			(layer "F.Fab")
		)
		(fp_line
			(start -0.12065 0.2794)
			(end -0.12065 0.3048)
			(stroke
				(width 0.1)
				(type default)
			)
			(layer "F.Fab")
		)
		(fp_line
			(start 0.67945 0.3048)
			(end 0.120396 0.3048)
			(stroke
				(width 0.1)
				(type default)
			)
			(layer "F.Fab")
		)
		(fp_line
			(start 0.120396 0.3048)
			(end 0.120396 0.2794)
			(stroke
				(width 0.1)
				(type default)
			)
			(layer "F.Fab")
		)
		(fp_line
			(start -0.12065 0.3048)
			(end -0.67945 0.3048)
			(stroke
				(width 0.1)
				(type default)
			)
			(layer "F.Fab")
		)
		(fp_line
			(start -0.67945 0.3048)
			(end -0.67945 -0.305054)
			(stroke
				(width 0.1)
				(type default)
			)
			(layer "F.Fab")
		)
		(pad "1" smd circle
			(at -0.40005 0 90)
			(size 0 0)
			(layers "F.Cu" "F.Mask" "F.Paste")
			(net "P12V_HSC_T_CRIT_N")
		)
		(pad "2" smd circle
			(at 0.40005 0 90)
			(size 0 0)
			(layers "F.Cu" "F.Mask" "F.Paste")
			(net "P12V_HSC_T_CRIT_R_N")
		)
	)
	(footprint ""
		(layer "F.Cu")
		(at 427.269656 -397.135604 180)
		(property "Reference" "L29"
			(at 0 0 180)
			(layer "F.SilkS")
			(hide yes)
			(effects
				(font
					(size 1.27 1.27)
				)
			)
		)
		(property "Value" ""
			(at 0 0 180)
			(layer "F.Fab")
			(effects
				(font
					(size 1.27 1.27)
				)
			)
		)
		(duplicate_pad_numbers_are_jumpers no)
		(fp_line
			(start 0.762 0.381)
			(end -0.762 0.381)
			(stroke
				(width 0.1524)
				(type default)
			)
			(layer "F.SilkS")
		)
		(fp_line
			(start 0.762 -0.381)
			(end 0.762 0.381)
			(stroke
				(width 0.1524)
				(type default)
			)
			(layer "F.SilkS")
		)
		(fp_line
			(start -0.762 0.381)
			(end -0.762 -0.381)
			(stroke
				(width 0.1524)
				(type default)
			)
			(layer "F.SilkS")
		)
		(fp_line
			(start -0.762 -0.381)
			(end 0.762 -0.381)
			(stroke
				(width 0.1524)
				(type default)
			)
			(layer "F.SilkS")
		)
		(fp_line
			(start 0.680466 0.306324)
			(end 0.118364 0.306324)
			(stroke
				(width 0.1)
				(type default)
			)
			(layer "F.Fab")
		)
		(fp_line
			(start 0.680466 -0.306324)
			(end 0.680466 0.306324)
			(stroke
				(width 0.1)
				(type default)
			)
			(layer "F.Fab")
		)
		(fp_line
			(start 0.118872 -0.2794)
			(end 0.118872 -0.306324)
			(stroke
				(width 0.1)
				(type default)
			)
			(layer "F.Fab")
		)
		(fp_line
			(start 0.118872 -0.306324)
			(end 0.680466 -0.306324)
			(stroke
				(width 0.1)
				(type default)
			)
			(layer "F.Fab")
		)
		(fp_line
			(start 0.118364 0.306324)
			(end 0.118364 0.2794)
			(stroke
				(width 0.1)
				(type default)
			)
			(layer "F.Fab")
		)
		(fp_line
			(start 0.118364 0.2794)
			(end -0.119634 0.2794)
			(stroke
				(width 0.1)
				(type default)
			)
			(layer "F.Fab")
		)
		(fp_line
			(start -0.118364 -0.2794)
			(end 0.118872 -0.2794)
			(stroke
				(width 0.1)
				(type default)
			)
			(layer "F.Fab")
		)
		(fp_line
			(start -0.118364 -0.307086)
			(end -0.118364 -0.2794)
			(stroke
				(width 0.1)
				(type default)
			)
			(layer "F.Fab")
		)
		(fp_line
			(start -0.119634 0.30607)
			(end -0.681736 0.30607)
			(stroke
				(width 0.1)
				(type default)
			)
			(layer "F.Fab")
		)
		(fp_line
			(start -0.119634 0.2794)
			(end -0.119634 0.30607)
			(stroke
				(width 0.1)
				(type default)
			)
			(layer "F.Fab")
		)
		(fp_line
			(start -0.681736 0.30607)
			(end -0.681736 -0.307086)
			(stroke
				(width 0.1)
				(type default)
			)
			(layer "F.Fab")
		)
		(fp_line
			(start -0.681736 -0.307086)
			(end -0.118364 -0.307086)
			(stroke
				(width 0.1)
				(type default)
			)
			(layer "F.Fab")
		)
		(pad "1" smd rect
			(at -0.40005 0)
			(size 0.4572 0.508)
			(layers "F.Cu" "F.Mask" "F.Paste")
			(net "P1V8_CPU0_RT_1D")
		)
		(pad "2" smd rect
			(at 0.40005 0)
			(size 0.4572 0.508)
			(layers "F.Cu" "F.Mask" "F.Paste")
			(net "P1V8_CPU0_RT2_1A_1D")
		)
	)
)
